#ISCELL
  pure_quanta quanta_title_block_c *
  *
#ISCELL
  standard offpage *
  page118_i100
#CELL
  pure_quanta q_res *
  page118_i101
#CELL
  pure_quanta q_res *
  page118_i102
#ISCELL
  standard offpage *
  page118_i12
#CELL
  pure_quanta q_res *
  page118_i23
#ISCELL
  standard offpage *
  page118_i55
#CELL
  pure_quanta q_res *
  page118_i63
#ISCELL
  standard offpage *
  page118_i64
#CELL
  pure_quanta q_res *
  page118_i65
#ISCELL
  logical_power universal_power *
  page118_i66
#CELL
  pure_quanta q_res *
  page118_i67
#ISCELL
  logical_power universal_power *
  page118_i68
#CELL
  pure_quanta q_res *
  page118_i73
#ISCELL
  logical_power universal_power *
  page118_i74
#CELL
  pure_quanta q_res *
  page118_i76
#ISCELL
  logical_power universal_power *
  page118_i78
#ISCELL
  standard offpage *
  page118_i79
#ISCELL
  standard offpage *
  page118_i80
#ISCELL
  standard offpage *
  page118_i84
#CELL
  pure_quanta q_res *
  page118_i92
#ISCELL
  standard offpage *
  page118_i98
